(kicad_pcb
	(version 20260206)
	(generator "pcbnew")
	(generator_version "10.0")
	(general
		(thickness 1.6)
		(legacy_teardrops no)
	)
	(paper "A4")
	(title_block
		(title "03242023_DA0F0TMBIJ0_F0T_Motherboard_J_brd_V01_OCP.brd")
		(comment 1 "Grand Teton / footprints 2293-2298 of 6105")
	)
	(layers
		(0 "F.Cu" signal "TOP")
		(4 "In1.Cu" signal "GND")
		(6 "In2.Cu" signal "IN1")
		(8 "In3.Cu" signal "GND1")
		(10 "In4.Cu" signal "IN2")
		(12 "In5.Cu" signal "GND2")
		(14 "In6.Cu" signal "IN3")
		(16 "In7.Cu" signal "GND3")
		(18 "In8.Cu" signal "VCC")
		(20 "In9.Cu" signal "VCC1")
		(22 "In10.Cu" signal "GND4")
		(24 "In11.Cu" signal "IN4")
		(26 "In12.Cu" signal "GND5")
		(28 "In13.Cu" signal "IN5")
		(30 "In14.Cu" signal "GND6")
		(32 "In15.Cu" signal "IN6")
		(34 "In16.Cu" signal "GND7")
		(2 "B.Cu" signal "BOTTOM")
		(9 "F.Adhes" user "F.Adhesive")
		(11 "B.Adhes" user "B.Adhesive")
		(13 "F.Paste" user "Package Geometry/Pastemask Top")
		(15 "B.Paste" user "Package Geometry/Pastemask Bottom")
		(5 "F.SilkS" user "Ref Des/Silkscreen Top")
		(7 "B.SilkS" user "Ref Des/Silkscreen Bottom")
		(1 "F.Mask" user "Board Geometry/Soldermask Top")
		(3 "B.Mask" user "Board Geometry/Soldermask Bottom")
		(17 "Dwgs.User" user "User.Drawings")
		(19 "Cmts.User" user "User.Comments")
		(21 "Eco1.User" user "User.Eco1")
		(23 "Eco2.User" user "User.Eco2")
		(25 "Edge.Cuts" user "Board Geometry/Outline")
		(27 "Margin" user)
		(31 "F.CrtYd" user "Package Geometry/Place Bound Top")
		(29 "B.CrtYd" user "Package Geometry/Place Bound Bottom")
		(35 "F.Fab" user "Ref Des/Assembly Top")
		(33 "B.Fab" user "Ref Des/Assembly Bottom")
	)
	(footprint ""
		(layer "F.Cu")
		(at 354.268278 -238.162338 -90)
		(property "Reference" "C1039"
			(at 0 0 270)
			(layer "F.SilkS")
			(hide yes)
			(effects
				(font
					(size 1.27 1.27)
				)
			)
		)
		(property "Value" ""
			(at 0 0 270)
			(layer "F.Fab")
			(effects
				(font
					(size 1.27 1.27)
				)
			)
		)
		(duplicate_pad_numbers_are_jumpers no)
		(fp_line
			(start -0.7874 0.4064)
			(end -0.7874 -0.4064)
			(stroke
				(width 0.1524)
				(type default)
			)
			(layer "F.SilkS")
		)
		(fp_line
			(start 0.7874 0.4064)
			(end -0.7874 0.4064)
			(stroke
				(width 0.1524)
				(type default)
			)
			(layer "F.SilkS")
		)
		(fp_line
			(start -0.7874 -0.4064)
			(end 0.7874 -0.4064)
			(stroke
				(width 0.1524)
				(type default)
			)
			(layer "F.SilkS")
		)
		(fp_line
			(start 0.7874 -0.4064)
			(end 0.7874 0.4064)
			(stroke
				(width 0.1524)
				(type default)
			)
			(layer "F.SilkS")
		)
		(fp_line
			(start -0.67945 0.3048)
			(end -0.67945 -0.305054)
			(stroke
				(width 0.1)
				(type default)
			)
			(layer "F.Fab")
		)
		(fp_line
			(start -0.12065 0.3048)
			(end -0.67945 0.3048)
			(stroke
				(width 0.1)
				(type default)
			)
			(layer "F.Fab")
		)
		(fp_line
			(start 0.120396 0.3048)
			(end 0.120396 0.2794)
			(stroke
				(width 0.1)
				(type default)
			)
			(layer "F.Fab")
		)
		(fp_line
			(start 0.67945 0.3048)
			(end 0.120396 0.3048)
			(stroke
				(width 0.1)
				(type default)
			)
			(layer "F.Fab")
		)
		(fp_line
			(start -0.12065 0.2794)
			(end -0.12065 0.3048)
			(stroke
				(width 0.1)
				(type default)
			)
			(layer "F.Fab")
		)
		(fp_line
			(start 0.120396 0.2794)
			(end -0.12065 0.2794)
			(stroke
				(width 0.1)
				(type default)
			)
			(layer "F.Fab")
		)
		(fp_line
			(start -0.12065 -0.2794)
			(end 0.12065 -0.2794)
			(stroke
				(width 0.1)
				(type default)
			)
			(layer "F.Fab")
		)
		(fp_line
			(start 0.12065 -0.2794)
			(end 0.12065 -0.3048)
			(stroke
				(width 0.1)
				(type default)
			)
			(layer "F.Fab")
		)
		(fp_line
			(start 0.12065 -0.3048)
			(end 0.67945 -0.3048)
			(stroke
				(width 0.1)
				(type default)
			)
			(layer "F.Fab")
		)
		(fp_line
			(start 0.67945 -0.3048)
			(end 0.67945 0.3048)
			(stroke
				(width 0.1)
				(type default)
			)
			(layer "F.Fab")
		)
		(fp_line
			(start -0.67945 -0.305054)
			(end -0.12065 -0.305054)
			(stroke
				(width 0.1)
				(type default)
			)
			(layer "F.Fab")
		)
		(fp_line
			(start -0.12065 -0.305054)
			(end -0.12065 -0.2794)
			(stroke
				(width 0.1)
				(type default)
			)
			(layer "F.Fab")
		)
		(pad "1" smd circle
			(at -0.40005 0 270)
			(size 0 0)
			(layers "F.Cu" "F.Mask" "F.Paste")
			(net "PVCCIN_CPU0")
		)
		(pad "2" smd circle
			(at 0.40005 0 270)
			(size 0 0)
			(layers "F.Cu" "F.Mask" "F.Paste")
			(net "GND")
		)
	)
	(footprint ""
		(layer "F.Cu")
		(at 21.176996 -98.171508)
		(property "Reference" "R3665"
			(at 0 0 0)
			(layer "F.SilkS")
			(hide yes)
			(effects
				(font
					(size 1.27 1.27)
				)
			)
		)
		(property "Value" ""
			(at 0 0 0)
			(layer "F.Fab")
			(effects
				(font
					(size 1.27 1.27)
				)
			)
		)
		(duplicate_pad_numbers_are_jumpers no)
		(fp_line
			(start -0.7874 -0.4064)
			(end 0.7874 -0.4064)
			(stroke
				(width 0.1524)
				(type default)
			)
			(layer "F.SilkS")
		)
		(fp_line
			(start -0.7874 0.4064)
			(end -0.7874 -0.4064)
			(stroke
				(width 0.1524)
				(type default)
			)
			(layer "F.SilkS")
		)
		(fp_line
			(start 0.7874 -0.4064)
			(end 0.7874 0.4064)
			(stroke
				(width 0.1524)
				(type default)
			)
			(layer "F.SilkS")
		)
		(fp_line
			(start 0.7874 0.4064)
			(end -0.7874 0.4064)
			(stroke
				(width 0.1524)
				(type default)
			)
			(layer "F.SilkS")
		)
		(fp_line
			(start -0.67945 -0.305054)
			(end -0.12065 -0.305054)
			(stroke
				(width 0.1)
				(type default)
			)
			(layer "F.Fab")
		)
		(fp_line
			(start -0.67945 0.3048)
			(end -0.67945 -0.305054)
			(stroke
				(width 0.1)
				(type default)
			)
			(layer "F.Fab")
		)
		(fp_line
			(start -0.12065 -0.305054)
			(end -0.12065 -0.2794)
			(stroke
				(width 0.1)
				(type default)
			)
			(layer "F.Fab")
		)
		(fp_line
			(start -0.12065 -0.2794)
			(end 0.12065 -0.2794)
			(stroke
				(width 0.1)
				(type default)
			)
			(layer "F.Fab")
		)
		(fp_line
			(start -0.12065 0.2794)
			(end -0.12065 0.3048)
			(stroke
				(width 0.1)
				(type default)
			)
			(layer "F.Fab")
		)
		(fp_line
			(start -0.12065 0.3048)
			(end -0.67945 0.3048)
			(stroke
				(width 0.1)
				(type default)
			)
			(layer "F.Fab")
		)
		(fp_line
			(start 0.120396 0.2794)
			(end -0.12065 0.2794)
			(stroke
				(width 0.1)
				(type default)
			)
			(layer "F.Fab")
		)
		(fp_line
			(start 0.120396 0.3048)
			(end 0.120396 0.2794)
			(stroke
				(width 0.1)
				(type default)
			)
			(layer "F.Fab")
		)
		(fp_line
			(start 0.12065 -0.3048)
			(end 0.67945 -0.3048)
			(stroke
				(width 0.1)
				(type default)
			)
			(layer "F.Fab")
		)
		(fp_line
			(start 0.12065 -0.2794)
			(end 0.12065 -0.3048)
			(stroke
				(width 0.1)
				(type default)
			)
			(layer "F.Fab")
		)
		(fp_line
			(start 0.67945 -0.3048)
			(end 0.67945 0.3048)
			(stroke
				(width 0.1)
				(type default)
			)
			(layer "F.Fab")
		)
		(fp_line
			(start 0.67945 0.3048)
			(end 0.120396 0.3048)
			(stroke
				(width 0.1)
				(type default)
			)
			(layer "F.Fab")
		)
		(pad "1" smd circle
			(at -0.40005 0)
			(size 0 0)
			(layers "F.Cu" "F.Mask" "F.Paste")
			(net "USB_HUB_PGANG")
		)
		(pad "2" smd circle
			(at 0.40005 0)
			(size 0 0)
			(layers "F.Cu" "F.Mask" "F.Paste")
			(net "GND")
		)
	)
	(footprint ""
		(layer "F.Cu")
		(at 149.75078 -124.005848)
		(property "Reference" "R3154"
			(at 0 0 0)
			(layer "F.SilkS")
			(hide yes)
			(effects
				(font
					(size 1.27 1.27)
				)
			)
		)
		(property "Value" ""
			(at 0 0 0)
			(layer "F.Fab")
			(effects
				(font
					(size 1.27 1.27)
				)
			)
		)
		(duplicate_pad_numbers_are_jumpers no)
		(fp_line
			(start -0.7874 -0.4064)
			(end 0.7874 -0.4064)
			(stroke
				(width 0.1524)
				(type default)
			)
			(layer "F.SilkS")
		)
		(fp_line
			(start -0.7874 0.4064)
			(end -0.7874 -0.4064)
			(stroke
				(width 0.1524)
				(type default)
			)
			(layer "F.SilkS")
		)
		(fp_line
			(start 0.7874 -0.4064)
			(end 0.7874 0.4064)
			(stroke
				(width 0.1524)
				(type default)
			)
			(layer "F.SilkS")
		)
		(fp_line
			(start 0.7874 0.4064)
			(end -0.7874 0.4064)
			(stroke
				(width 0.1524)
				(type default)
			)
			(layer "F.SilkS")
		)
		(fp_line
			(start -0.67945 -0.305054)
			(end -0.12065 -0.305054)
			(stroke
				(width 0.1)
				(type default)
			)
			(layer "F.Fab")
		)
		(fp_line
			(start -0.67945 0.3048)
			(end -0.67945 -0.305054)
			(stroke
				(width 0.1)
				(type default)
			)
			(layer "F.Fab")
		)
		(fp_line
			(start -0.12065 -0.305054)
			(end -0.12065 -0.2794)
			(stroke
				(width 0.1)
				(type default)
			)
			(layer "F.Fab")
		)
		(fp_line
			(start -0.12065 -0.2794)
			(end 0.12065 -0.2794)
			(stroke
				(width 0.1)
				(type default)
			)
			(layer "F.Fab")
		)
		(fp_line
			(start -0.12065 0.2794)
			(end -0.12065 0.3048)
			(stroke
				(width 0.1)
				(type default)
			)
			(layer "F.Fab")
		)
		(fp_line
			(start -0.12065 0.3048)
			(end -0.67945 0.3048)
			(stroke
				(width 0.1)
				(type default)
			)
			(layer "F.Fab")
		)
		(fp_line
			(start 0.120396 0.2794)
			(end -0.12065 0.2794)
			(stroke
				(width 0.1)
				(type default)
			)
			(layer "F.Fab")
		)
		(fp_line
			(start 0.120396 0.3048)
			(end 0.120396 0.2794)
			(stroke
				(width 0.1)
				(type default)
			)
			(layer "F.Fab")
		)
		(fp_line
			(start 0.12065 -0.3048)
			(end 0.67945 -0.3048)
			(stroke
				(width 0.1)
				(type default)
			)
			(layer "F.Fab")
		)
		(fp_line
			(start 0.12065 -0.2794)
			(end 0.12065 -0.3048)
			(stroke
				(width 0.1)
				(type default)
			)
			(layer "F.Fab")
		)
		(fp_line
			(start 0.67945 -0.3048)
			(end 0.67945 0.3048)
			(stroke
				(width 0.1)
				(type default)
			)
			(layer "F.Fab")
		)
		(fp_line
			(start 0.67945 0.3048)
			(end 0.120396 0.3048)
			(stroke
				(width 0.1)
				(type default)
			)
			(layer "F.Fab")
		)
		(pad "1" smd circle
			(at -0.40005 0)
			(size 0 0)
			(layers "F.Cu" "F.Mask" "F.Paste")
			(net "PD_SMB_OCP2_HP_ADD0")
		)
		(pad "2" smd circle
			(at 0.40005 0)
			(size 0 0)
			(layers "F.Cu" "F.Mask" "F.Paste")
			(net "GND")
		)
	)
	(footprint ""
		(layer "F.Cu")
		(at 106.476038 -39.996364)
		(property "Reference" "R3186"
			(at 0 0 0)
			(layer "F.SilkS")
			(hide yes)
			(effects
				(font
					(size 1.27 1.27)
				)
			)
		)
		(property "Value" ""
			(at 0 0 0)
			(layer "F.Fab")
			(effects
				(font
					(size 1.27 1.27)
				)
			)
		)
		(duplicate_pad_numbers_are_jumpers no)
		(fp_line
			(start -0.7874 -0.4064)
			(end 0.7874 -0.4064)
			(stroke
				(width 0.1524)
				(type default)
			)
			(layer "F.SilkS")
		)
		(fp_line
			(start -0.7874 0.4064)
			(end -0.7874 -0.4064)
			(stroke
				(width 0.1524)
				(type default)
			)
			(layer "F.SilkS")
		)
		(fp_line
			(start 0.7874 -0.4064)
			(end 0.7874 0.4064)
			(stroke
				(width 0.1524)
				(type default)
			)
			(layer "F.SilkS")
		)
		(fp_line
			(start 0.7874 0.4064)
			(end -0.7874 0.4064)
			(stroke
				(width 0.1524)
				(type default)
			)
			(layer "F.SilkS")
		)
		(fp_line
			(start -0.67945 -0.305054)
			(end -0.12065 -0.305054)
			(stroke
				(width 0.1)
				(type default)
			)
			(layer "F.Fab")
		)
		(fp_line
			(start -0.67945 0.3048)
			(end -0.67945 -0.305054)
			(stroke
				(width 0.1)
				(type default)
			)
			(layer "F.Fab")
		)
		(fp_line
			(start -0.12065 -0.305054)
			(end -0.12065 -0.2794)
			(stroke
				(width 0.1)
				(type default)
			)
			(layer "F.Fab")
		)
		(fp_line
			(start -0.12065 -0.2794)
			(end 0.12065 -0.2794)
			(stroke
				(width 0.1)
				(type default)
			)
			(layer "F.Fab")
		)
		(fp_line
			(start -0.12065 0.2794)
			(end -0.12065 0.3048)
			(stroke
				(width 0.1)
				(type default)
			)
			(layer "F.Fab")
		)
		(fp_line
			(start -0.12065 0.3048)
			(end -0.67945 0.3048)
			(stroke
				(width 0.1)
				(type default)
			)
			(layer "F.Fab")
		)
		(fp_line
			(start 0.120396 0.2794)
			(end -0.12065 0.2794)
			(stroke
				(width 0.1)
				(type default)
			)
			(layer "F.Fab")
		)
		(fp_line
			(start 0.120396 0.3048)
			(end 0.120396 0.2794)
			(stroke
				(width 0.1)
				(type default)
			)
			(layer "F.Fab")
		)
		(fp_line
			(start 0.12065 -0.3048)
			(end 0.67945 -0.3048)
			(stroke
				(width 0.1)
				(type default)
			)
			(layer "F.Fab")
		)
		(fp_line
			(start 0.12065 -0.2794)
			(end 0.12065 -0.3048)
			(stroke
				(width 0.1)
				(type default)
			)
			(layer "F.Fab")
		)
		(fp_line
			(start 0.67945 -0.3048)
			(end 0.67945 0.3048)
			(stroke
				(width 0.1)
				(type default)
			)
			(layer "F.Fab")
		)
		(fp_line
			(start 0.67945 0.3048)
			(end 0.120396 0.3048)
			(stroke
				(width 0.1)
				(type default)
			)
			(layer "F.Fab")
		)
		(pad "1" smd circle
			(at -0.40005 0)
			(size 0 0)
			(layers "F.Cu" "F.Mask" "F.Paste")
			(net "RST_OCP_V3_2_BUF_N")
		)
		(pad "2" smd circle
			(at 0.40005 0)
			(size 0 0)
			(layers "F.Cu" "F.Mask" "F.Paste")
			(net "RST_PERST0_OCP_V3_2_N")
		)
	)
	(footprint ""
		(layer "F.Cu")
		(at 65.90411 -17.941544 180)
		(property "Reference" "C1829"
			(at 0 0 180)
			(layer "F.SilkS")
			(hide yes)
			(effects
				(font
					(size 1.27 1.27)
				)
			)
		)
		(property "Value" ""
			(at 0 0 180)
			(layer "F.Fab")
			(effects
				(font
					(size 1.27 1.27)
				)
			)
		)
		(duplicate_pad_numbers_are_jumpers no)
		(fp_line
			(start 1.524 0.762)
			(end -1.524 0.762)
			(stroke
				(width 0.1524)
				(type default)
			)
			(layer "F.SilkS")
		)
		(fp_line
			(start 1.524 -0.762)
			(end 1.524 0.762)
			(stroke
				(width 0.1524)
				(type default)
			)
			(layer "F.SilkS")
		)
		(fp_line
			(start -1.524 0.762)
			(end -1.524 -0.762)
			(stroke
				(width 0.1524)
				(type default)
			)
			(layer "F.SilkS")
		)
		(fp_line
			(start -1.524 -0.762)
			(end 1.524 -0.762)
			(stroke
				(width 0.1524)
				(type default)
			)
			(layer "F.SilkS")
		)
		(fp_line
			(start 1.1049 0.724916)
			(end 1.1049 -0.724916)
			(stroke
				(width 0.1)
				(type default)
			)
			(layer "F.Fab")
		)
		(fp_line
			(start 1.1049 -0.724916)
			(end -1.1049 -0.724916)
			(stroke
				(width 0.1)
				(type default)
			)
			(layer "F.Fab")
		)
		(fp_line
			(start -1.1049 0.724916)
			(end 1.1049 0.724916)
			(stroke
				(width 0.1)
				(type default)
			)
			(layer "F.Fab")
		)
		(fp_line
			(start -1.1049 -0.724916)
			(end -1.1049 0.724916)
			(stroke
				(width 0.1)
				(type default)
			)
			(layer "F.Fab")
		)
		(pad "1" smd rect
			(at -0.889 0)
			(size 1.016 1.27)
			(layers "F.Cu" "F.Mask" "F.Paste")
			(net "P12V_OCP_V3_2")
		)
		(pad "2" smd rect
			(at 0.889 0)
			(size 1.016 1.27)
			(layers "F.Cu" "F.Mask" "F.Paste")
			(net "GND")
		)
	)
	(footprint ""
		(layer "F.Cu")
		(at 114.70386 -363.508036)
		(property "Reference" "PC2366"
			(at 0 0 0)
			(layer "F.SilkS")
			(hide yes)
			(effects
				(font
					(size 1.27 1.27)
				)
			)
		)
		(property "Value" ""
			(at 0 0 0)
			(layer "F.Fab")
			(effects
				(font
					(size 1.27 1.27)
				)
			)
		)
		(duplicate_pad_numbers_are_jumpers no)
		(fp_line
			(start -0.7874 -0.4064)
			(end 0.7874 -0.4064)
			(stroke
				(width 0.1524)
				(type default)
			)
			(layer "F.SilkS")
		)
		(fp_line
			(start -0.7874 0.4064)
			(end -0.7874 -0.4064)
			(stroke
				(width 0.1524)
				(type default)
			)
			(layer "F.SilkS")
		)
		(fp_line
			(start 0.7874 -0.4064)
			(end 0.7874 0.4064)
			(stroke
				(width 0.1524)
				(type default)
			)
			(layer "F.SilkS")
		)
		(fp_line
			(start 0.7874 0.4064)
			(end -0.7874 0.4064)
			(stroke
				(width 0.1524)
				(type default)
			)
			(layer "F.SilkS")
		)
		(fp_line
			(start -0.67945 -0.305054)
			(end -0.12065 -0.305054)
			(stroke
				(width 0.1)
				(type default)
			)
			(layer "F.Fab")
		)
		(fp_line
			(start -0.67945 0.3048)
			(end -0.67945 -0.305054)
			(stroke
				(width 0.1)
				(type default)
			)
			(layer "F.Fab")
		)
		(fp_line
			(start -0.12065 -0.305054)
			(end -0.12065 -0.2794)
			(stroke
				(width 0.1)
				(type default)
			)
			(layer "F.Fab")
		)
		(fp_line
			(start -0.12065 -0.2794)
			(end 0.12065 -0.2794)
			(stroke
				(width 0.1)
				(type default)
			)
			(layer "F.Fab")
		)
		(fp_line
			(start -0.12065 0.2794)
			(end -0.12065 0.3048)
			(stroke
				(width 0.1)
				(type default)
			)
			(layer "F.Fab")
		)
		(fp_line
			(start -0.12065 0.3048)
			(end -0.67945 0.3048)
			(stroke
				(width 0.1)
				(type default)
			)
			(layer "F.Fab")
		)
		(fp_line
			(start 0.120396 0.2794)
			(end -0.12065 0.2794)
			(stroke
				(width 0.1)
				(type default)
			)
			(layer "F.Fab")
		)
		(fp_line
			(start 0.120396 0.3048)
			(end 0.120396 0.2794)
			(stroke
				(width 0.1)
				(type default)
			)
			(layer "F.Fab")
		)
		(fp_line
			(start 0.12065 -0.3048)
			(end 0.67945 -0.3048)
			(stroke
				(width 0.1)
				(type default)
			)
			(layer "F.Fab")
		)
		(fp_line
			(start 0.12065 -0.2794)
			(end 0.12065 -0.3048)
			(stroke
				(width 0.1)
				(type default)
			)
			(layer "F.Fab")
		)
		(fp_line
			(start 0.67945 -0.3048)
			(end 0.67945 0.3048)
			(stroke
				(width 0.1)
				(type default)
			)
			(layer "F.Fab")
		)
		(fp_line
			(start 0.67945 0.3048)
			(end 0.120396 0.3048)
			(stroke
				(width 0.1)
				(type default)
			)
			(layer "F.Fab")
		)
		(pad "1" smd circle
			(at -0.40005 0)
			(size 0 0)
			(layers "F.Cu" "F.Mask" "F.Paste")
			(net "PVCCIN_CPU1_VCC")
		)
		(pad "2" smd circle
			(at 0.40005 0)
			(size 0 0)
			(layers "F.Cu" "F.Mask" "F.Paste")
			(net "GND")
		)
	)
)
